(kicad_pcb
	(version 20260206)
	(generator "pcbnew")
	(generator_version "10.0")
	(general
		(thickness 1.6)
		(legacy_teardrops no)
	)
	(paper "A4")
	(title_block
		(title "Bryce Canyon_F.DPB_16315-1-OCP.brd")
		(comment 1 "Bryce Canyon / footprints 382-389 of 2223")
	)
	(layers
		(0 "F.Cu" signal "TOP")
		(4 "In1.Cu" signal "L2GND")
		(6 "In2.Cu" signal "L3")
		(8 "In3.Cu" signal "L4GND")
		(10 "In4.Cu" signal "L5")
		(12 "In5.Cu" signal "L6VCC")
		(14 "In6.Cu" signal "L7VCC")
		(16 "In7.Cu" signal "L8")
		(18 "In8.Cu" signal "L9GND")
		(20 "In9.Cu" signal "L10")
		(22 "In10.Cu" signal "L11GND")
		(2 "B.Cu" signal "BOTTOM")
		(9 "F.Adhes" user "F.Adhesive")
		(11 "B.Adhes" user "B.Adhesive")
		(13 "F.Paste" user "Package Geometry/Pastemask Top")
		(15 "B.Paste" user "Package Geometry/Pastemask Bottom")
		(5 "F.SilkS" user "Ref Des/Silkscreen Top")
		(7 "B.SilkS" user "Ref Des/Silkscreen Bottom")
		(1 "F.Mask" user "Board Geometry/Soldermask Top")
		(3 "B.Mask" user "Board Geometry/Soldermask Bottom")
		(17 "Dwgs.User" user "User.Drawings")
		(19 "Cmts.User" user "User.Comments")
		(21 "Eco1.User" user "User.Eco1")
		(23 "Eco2.User" user "User.Eco2")
		(25 "Edge.Cuts" user "Board Geometry/Outline")
		(27 "Margin" user)
		(31 "F.CrtYd" user "Package Geometry/Place Bound Top")
		(29 "B.CrtYd" user "Package Geometry/Place Bound Bottom")
		(35 "F.Fab" user "Ref Des/Assembly Top")
		(33 "B.Fab" user "Ref Des/Assembly Bottom")
	)
	(footprint ""
		(layer "F.Cu")
		(at 253.603506 -261.324598 180)
		(property "Reference" "R59"
			(at 0 0 180)
			(layer "F.SilkS")
			(hide yes)
			(effects
				(font
					(size 1.27 1.27)
				)
			)
		)
		(property "Value" "0R2J-2-GP"
			(at 0.064008 -3.993896 180)
			(unlocked yes)
			(layer "F.Fab")
			(hide yes)
			(effects
				(font
					(size 1.016 1.016)
					(thickness 0.1524)
				)
			)
		)
		(property "Device Type" "R402H16"
			(at 0.064008 -5.517896 180)
			(unlocked yes)
			(layer "F.Fab")
			(hide yes)
			(effects
				(font
					(size 1.016 1.016)
					(thickness 0.1524)
				)
			)
		)
		(duplicate_pad_numbers_are_jumpers no)
		(fp_line
			(start 0.508 -0.9398)
			(end -0.508 -0.9398)
			(stroke
				(width 0.1524)
				(type default)
			)
			(layer "F.SilkS")
		)
		(fp_line
			(start -0.508 -0.9398)
			(end -0.508 0.9398)
			(stroke
				(width 0.1524)
				(type default)
			)
			(layer "F.SilkS")
		)
		(fp_rect
			(start -0.508 0.9398)
			(end 0.508 -0.9398)
			(stroke
				(width 0)
				(type default)
			)
			(fill no)
			(layer "F.CrtYd")
		)
		(fp_rect
			(start -0.508 0.9398)
			(end 0.508 -0.9398)
			(stroke
				(width 0)
				(type default)
			)
			(fill no)
			(layer "F.Fab")
		)
		(pad "1" smd custom
			(at 0 -0.4445 180)
			(size 0.1397 0.1397)
			(layers "F.Cu" "F.Mask" "F.Paste")
			(net "IO_EXP6_SDA")
			(options
				(clearance outline)
				(anchor circle)
			)
			(primitives
				(gr_poly
					(pts
						(arc
							(start -0.1778 -0.2794)
							(mid -0.249642 -0.249642)
							(end -0.2794 -0.1778)
						)
						(arc
							(start -0.2794 0.1778)
							(mid -0.249642 0.249642)
							(end -0.1778 0.2794)
						)
						(arc
							(start 0.1778 0.2794)
							(mid 0.249642 0.249642)
							(end 0.2794 0.1778)
						)
						(arc
							(start 0.2794 -0.1778)
							(mid 0.249642 -0.249642)
							(end 0.1778 -0.2794)
						)
					)
					(width 0)
					(fill yes)
				)
			)
		)
		(pad "2" smd custom
			(at 0 0.4445 180)
			(size 0.1397 0.1397)
			(layers "F.Cu" "F.Mask" "F.Paste")
			(net "I2C_DRIVE_A_INS_SDA")
			(options
				(clearance outline)
				(anchor circle)
			)
			(primitives
				(gr_poly
					(pts
						(arc
							(start -0.1778 -0.2794)
							(mid -0.249642 -0.249642)
							(end -0.2794 -0.1778)
						)
						(arc
							(start -0.2794 0.1778)
							(mid -0.249642 0.249642)
							(end -0.1778 0.2794)
						)
						(arc
							(start 0.1778 0.2794)
							(mid 0.249642 0.249642)
							(end 0.2794 0.1778)
						)
						(arc
							(start 0.2794 -0.1778)
							(mid 0.249642 -0.249642)
							(end 0.1778 -0.2794)
						)
					)
					(width 0)
					(fill yes)
				)
			)
		)
	)
	(footprint ""
		(layer "F.Cu")
		(at 210.898232 -9.492488 90)
		(property "Reference" "C42"
			(at 0 0 90)
			(layer "F.SilkS")
			(hide yes)
			(effects
				(font
					(size 1.27 1.27)
				)
			)
		)
		(property "Value" "SC1U16V3KX-5GP"
			(at 0 -2.8194 90)
			(unlocked yes)
			(layer "F.Fab")
			(hide yes)
			(effects
				(font
					(size 1.016 1.016)
					(thickness 0.1524)
				)
			)
		)
		(property "Device Type" "C603H36"
			(at 0 -4.3434 90)
			(unlocked yes)
			(layer "F.Fab")
			(hide yes)
			(effects
				(font
					(size 1.016 1.016)
					(thickness 0.1524)
				)
			)
		)
		(duplicate_pad_numbers_are_jumpers no)
		(fp_line
			(start 0.508 0)
			(end -0.508 0)
			(stroke
				(width 0.2032)
				(type default)
			)
			(layer "F.SilkS")
		)
		(fp_rect
			(start -0.5842 1.3335)
			(end 0.5842 -1.3335)
			(stroke
				(width 0)
				(type default)
			)
			(fill no)
			(layer "F.CrtYd")
		)
		(fp_rect
			(start -0.5842 1.3335)
			(end 0.5842 -1.3335)
			(stroke
				(width 0)
				(type default)
			)
			(fill no)
			(layer "F.Fab")
		)
		(pad "1" smd custom
			(at 0 -0.762 90)
			(size 0.2159 0.2159)
			(layers "F.Cu" "F.Mask" "F.Paste")
			(net "P5V_A_2")
			(options
				(clearance outline)
				(anchor circle)
			)
			(primitives
				(gr_poly
					(pts
						(arc
							(start -0.3302 -0.4318)
							(mid -0.402042 -0.402042)
							(end -0.4318 -0.3302)
						)
						(arc
							(start -0.4318 0.3302)
							(mid -0.402042 0.402042)
							(end -0.3302 0.4318)
						)
						(arc
							(start 0.3302 0.4318)
							(mid 0.402042 0.402042)
							(end 0.4318 0.3302)
						)
						(arc
							(start 0.4318 -0.3302)
							(mid 0.402042 -0.402042)
							(end 0.3302 -0.4318)
						)
					)
					(width 0)
					(fill yes)
				)
			)
		)
		(pad "2" smd custom
			(at 0 0.762 90)
			(size 0.2159 0.2159)
			(layers "F.Cu" "F.Mask" "F.Paste")
			(net "GND")
			(options
				(clearance outline)
				(anchor circle)
			)
			(primitives
				(gr_poly
					(pts
						(arc
							(start -0.3302 -0.4318)
							(mid -0.402042 -0.402042)
							(end -0.4318 -0.3302)
						)
						(arc
							(start -0.4318 0.3302)
							(mid -0.402042 0.402042)
							(end -0.3302 0.4318)
						)
						(arc
							(start 0.3302 0.4318)
							(mid 0.402042 0.402042)
							(end 0.4318 0.3302)
						)
						(arc
							(start 0.4318 -0.3302)
							(mid 0.402042 -0.402042)
							(end 0.3302 -0.4318)
						)
					)
					(width 0)
					(fill yes)
				)
			)
		)
	)
	(footprint ""
		(layer "F.Cu")
		(at 172.5422 -45.608494 90)
		(property "Reference" "R811"
			(at 0 0 90)
			(layer "F.SilkS")
			(hide yes)
			(effects
				(font
					(size 1.27 1.27)
				)
			)
		)
		(property "Value" "4K7R2J-2-GP"
			(at 0.064008 -3.993896 90)
			(unlocked yes)
			(layer "F.Fab")
			(hide yes)
			(effects
				(font
					(size 1.016 1.016)
					(thickness 0.1524)
				)
			)
		)
		(property "Device Type" "R402H16"
			(at 0.064008 -5.517896 90)
			(unlocked yes)
			(layer "F.Fab")
			(hide yes)
			(effects
				(font
					(size 1.016 1.016)
					(thickness 0.1524)
				)
			)
		)
		(duplicate_pad_numbers_are_jumpers no)
		(fp_line
			(start 0.508 -0.9398)
			(end -0.508 -0.9398)
			(stroke
				(width 0.1524)
				(type default)
			)
			(layer "F.SilkS")
		)
		(fp_line
			(start -0.508 -0.9398)
			(end -0.508 0.9398)
			(stroke
				(width 0.1524)
				(type default)
			)
			(layer "F.SilkS")
		)
		(fp_rect
			(start -0.508 0.9398)
			(end 0.508 -0.9398)
			(stroke
				(width 0)
				(type default)
			)
			(fill no)
			(layer "F.CrtYd")
		)
		(fp_rect
			(start -0.508 0.9398)
			(end 0.508 -0.9398)
			(stroke
				(width 0)
				(type default)
			)
			(fill no)
			(layer "F.Fab")
		)
		(pad "1" smd custom
			(at 0 -0.4445 90)
			(size 0.1397 0.1397)
			(layers "F.Cu" "F.Mask" "F.Paste")
			(net "P12V_A")
			(options
				(clearance outline)
				(anchor circle)
			)
			(primitives
				(gr_poly
					(pts
						(arc
							(start -0.1778 -0.2794)
							(mid -0.249642 -0.249642)
							(end -0.2794 -0.1778)
						)
						(arc
							(start -0.2794 0.1778)
							(mid -0.249642 0.249642)
							(end -0.1778 0.2794)
						)
						(arc
							(start 0.1778 0.2794)
							(mid 0.249642 0.249642)
							(end 0.2794 0.1778)
						)
						(arc
							(start 0.2794 -0.1778)
							(mid 0.249642 -0.249642)
							(end 0.1778 -0.2794)
						)
					)
					(width 0)
					(fill yes)
				)
			)
		)
		(pad "2" smd custom
			(at 0 0.4445 90)
			(size 0.1397 0.1397)
			(layers "F.Cu" "F.Mask" "F.Paste")
			(net "SW_HDD_R29")
			(options
				(clearance outline)
				(anchor circle)
			)
			(primitives
				(gr_poly
					(pts
						(arc
							(start -0.1778 -0.2794)
							(mid -0.249642 -0.249642)
							(end -0.2794 -0.1778)
						)
						(arc
							(start -0.2794 0.1778)
							(mid -0.249642 0.249642)
							(end -0.1778 0.2794)
						)
						(arc
							(start 0.1778 0.2794)
							(mid 0.249642 0.249642)
							(end 0.2794 0.1778)
						)
						(arc
							(start 0.2794 -0.1778)
							(mid 0.249642 -0.249642)
							(end 0.1778 -0.2794)
						)
					)
					(width 0)
					(fill yes)
				)
			)
		)
	)
	(footprint ""
		(layer "F.Cu")
		(at 412.912052 -177.169318 90)
		(property "Reference" "R613"
			(at 0 0 90)
			(layer "F.SilkS")
			(hide yes)
			(effects
				(font
					(size 1.27 1.27)
				)
			)
		)
		(property "Value" "10KR2F-2-GP"
			(at 0.064008 -3.993896 90)
			(unlocked yes)
			(layer "F.Fab")
			(hide yes)
			(effects
				(font
					(size 1.016 1.016)
					(thickness 0.1524)
				)
			)
		)
		(property "Device Type" "R402H16"
			(at 0.064008 -5.517896 90)
			(unlocked yes)
			(layer "F.Fab")
			(hide yes)
			(effects
				(font
					(size 1.016 1.016)
					(thickness 0.1524)
				)
			)
		)
		(duplicate_pad_numbers_are_jumpers no)
		(fp_line
			(start 0.508 -0.9398)
			(end -0.508 -0.9398)
			(stroke
				(width 0.1524)
				(type default)
			)
			(layer "F.SilkS")
		)
		(fp_line
			(start -0.508 -0.9398)
			(end -0.508 0.9398)
			(stroke
				(width 0.1524)
				(type default)
			)
			(layer "F.SilkS")
		)
		(fp_rect
			(start -0.508 0.9398)
			(end 0.508 -0.9398)
			(stroke
				(width 0)
				(type default)
			)
			(fill no)
			(layer "F.CrtYd")
		)
		(fp_rect
			(start -0.508 0.9398)
			(end 0.508 -0.9398)
			(stroke
				(width 0)
				(type default)
			)
			(fill no)
			(layer "F.Fab")
		)
		(pad "1" smd custom
			(at 0 -0.4445 90)
			(size 0.1397 0.1397)
			(layers "F.Cu" "F.Mask" "F.Paste")
			(net "P3V3_STBY_A")
			(options
				(clearance outline)
				(anchor circle)
			)
			(primitives
				(gr_poly
					(pts
						(arc
							(start -0.1778 -0.2794)
							(mid -0.249642 -0.249642)
							(end -0.2794 -0.1778)
						)
						(arc
							(start -0.2794 0.1778)
							(mid -0.249642 0.249642)
							(end -0.1778 0.2794)
						)
						(arc
							(start 0.1778 0.2794)
							(mid 0.249642 0.249642)
							(end 0.2794 0.1778)
						)
						(arc
							(start 0.2794 -0.1778)
							(mid 0.249642 -0.249642)
							(end 0.1778 -0.2794)
						)
					)
					(width 0)
					(fill yes)
				)
			)
		)
		(pad "2" smd custom
			(at 0 0.4445 90)
			(size 0.1397 0.1397)
			(layers "F.Cu" "F.Mask" "F.Paste")
			(net "HDD_PRSNT_21")
			(options
				(clearance outline)
				(anchor circle)
			)
			(primitives
				(gr_poly
					(pts
						(arc
							(start -0.1778 -0.2794)
							(mid -0.249642 -0.249642)
							(end -0.2794 -0.1778)
						)
						(arc
							(start -0.2794 0.1778)
							(mid -0.249642 0.249642)
							(end -0.1778 0.2794)
						)
						(arc
							(start 0.1778 0.2794)
							(mid 0.249642 0.249642)
							(end 0.2794 0.1778)
						)
						(arc
							(start 0.2794 -0.1778)
							(mid 0.249642 -0.249642)
							(end 0.1778 -0.2794)
						)
					)
					(width 0)
					(fill yes)
				)
			)
		)
	)
	(footprint ""
		(layer "F.Cu")
		(at 272.542 -352.305112 180)
		(property "Reference" "VIA41"
			(at 0 0 180)
			(layer "F.SilkS")
			(hide yes)
			(effects
				(font
					(size 1.27 1.27)
				)
			)
		)
		(property "Value" "100OHM-8L-1D6MM-L18L16-GP"
			(at -3.7211 -4.5085 180)
			(unlocked yes)
			(layer "F.Fab")
			(hide yes)
			(effects
				(font
					(size 1.016 1.016)
					(thickness 0.1524)
				)
			)
		)
		(property "Device Type" "VIA-PCIE-4P-394076"
			(at -3.7211 -6.0325 180)
			(unlocked yes)
			(layer "F.Fab")
			(hide yes)
			(effects
				(font
					(size 1.016 1.016)
					(thickness 0.1524)
				)
			)
		)
		(duplicate_pad_numbers_are_jumpers no)
		(fp_rect
			(start -1.9685 0.381)
			(end 1.9685 -0.381)
			(stroke
				(width 0)
				(type default)
			)
			(fill no)
			(layer "F.CrtYd")
		)
		(fp_rect
			(start -1.9685 0.381)
			(end 1.9685 -0.381)
			(stroke
				(width 0)
				(type default)
			)
			(fill no)
			(layer "F.Fab")
		)
		(pad "1" thru_hole circle
			(at -1.5875 0 180)
			(size 0.508 0.508)
			(drill 0.254)
			(layers "*.Cu" "*.Mask")
			(remove_unused_layers no)
			(net "GND")
			(clearance 0.127)
			(thermal_gap 0.127)
		)
		(pad "2" thru_hole circle
			(at -0.5715 0 180)
			(size 0.508 0.508)
			(drill 0.254)
			(layers "*.Cu" "*.Mask")
			(remove_unused_layers no)
			(net "PHY_SCC_A_TO_DRV_A_4_DP")
			(clearance 0.127)
			(thermal_gap 0.127)
		)
		(pad "3" thru_hole circle
			(at 0.5715 0 180)
			(size 0.508 0.508)
			(drill 0.254)
			(layers "*.Cu" "*.Mask")
			(remove_unused_layers no)
			(net "PHY_SCC_A_TO_DRV_A_4_DN")
			(clearance 0.127)
			(thermal_gap 0.127)
		)
		(pad "4" thru_hole circle
			(at 1.5875 0 180)
			(size 0.508 0.508)
			(drill 0.254)
			(layers "*.Cu" "*.Mask")
			(remove_unused_layers no)
			(net "GND")
			(clearance 0.127)
			(thermal_gap 0.127)
		)
	)
	(footprint ""
		(layer "F.Cu")
		(at 384.734562 -159.219392 -90)
		(property "Reference" "C298"
			(at 0 0 270)
			(layer "F.SilkS")
			(hide yes)
			(effects
				(font
					(size 1.27 1.27)
				)
			)
		)
		(property "Value" "SCD01U16V1KX-GP"
			(at -2.8321 -1.7399 270)
			(unlocked yes)
			(layer "F.Fab")
			(hide yes)
			(effects
				(font
					(size 1.016 1.016)
					(thickness 0.1524)
				)
			)
		)
		(property "Device Type" "C0201H13"
			(at -2.8321 -3.2639 270)
			(unlocked yes)
			(layer "F.Fab")
			(hide yes)
			(effects
				(font
					(size 1.016 1.016)
					(thickness 0.1524)
				)
			)
		)
		(duplicate_pad_numbers_are_jumpers no)
		(fp_rect
			(start -0.2794 0.6477)
			(end 0.2794 -0.6477)
			(stroke
				(width 0)
				(type default)
			)
			(fill no)
			(layer "F.CrtYd")
		)
		(fp_rect
			(start -0.2794 0.6477)
			(end 0.2794 -0.6477)
			(stroke
				(width 0)
				(type default)
			)
			(fill no)
			(layer "F.Fab")
		)
		(pad "1" smd custom
			(at 0 -0.2794 270)
			(size 0.0762 0.0762)
			(layers "F.Cu" "F.Mask" "F.Paste")
			(net "SAS_HDD_RX_N20")
			(options
				(clearance outline)
				(anchor circle)
			)
			(primitives
				(gr_poly
					(pts
						(arc
							(start 0.1524 -0.127)
							(mid 0.137521 -0.162921)
							(end 0.1016 -0.1778)
						)
						(arc
							(start -0.1016 -0.1778)
							(mid -0.137521 -0.162921)
							(end -0.1524 -0.127)
						)
						(arc
							(start -0.1524 0.127)
							(mid -0.137521 0.162921)
							(end -0.1016 0.1778)
						)
						(arc
							(start 0.1016 0.1778)
							(mid 0.137521 0.162921)
							(end 0.1524 0.127)
						)
					)
					(width 0)
					(fill yes)
				)
			)
		)
		(pad "2" smd custom
			(at 0 0.2794 270)
			(size 0.0762 0.0762)
			(layers "F.Cu" "F.Mask" "F.Paste")
			(net "PHY_SCC_A_TO_DRV_A_20_DN")
			(options
				(clearance outline)
				(anchor circle)
			)
			(primitives
				(gr_poly
					(pts
						(arc
							(start 0.1524 -0.127)
							(mid 0.137521 -0.162921)
							(end 0.1016 -0.1778)
						)
						(arc
							(start -0.1016 -0.1778)
							(mid -0.137521 -0.162921)
							(end -0.1524 -0.127)
						)
						(arc
							(start -0.1524 0.127)
							(mid -0.137521 0.162921)
							(end -0.1016 0.1778)
						)
						(arc
							(start 0.1016 0.1778)
							(mid 0.137521 0.162921)
							(end 0.1524 0.127)
						)
					)
					(width 0)
					(fill yes)
				)
			)
		)
	)
	(footprint ""
		(layer "F.Cu")
		(at 51.980846 -278.554942 180)
		(property "Reference" "Q7"
			(at 0 0 180)
			(layer "F.SilkS")
			(hide yes)
			(effects
				(font
					(size 1.27 1.27)
				)
			)
		)
		(property "Value" "2N7002KDW-GP"
			(at -2.3622 -8.2042 180)
			(unlocked yes)
			(layer "F.Fab")
			(hide yes)
			(effects
				(font
					(size 1.016 1.016)
					(thickness 0.1524)
				)
			)
		)
		(property "Device Type" "SOT-363H44"
			(at -2.3622 -10.1092 180)
			(unlocked yes)
			(layer "F.Fab")
			(hide yes)
			(effects
				(font
					(size 1.016 1.016)
					(thickness 0.1524)
				)
			)
		)
		(duplicate_pad_numbers_are_jumpers no)
		(fp_line
			(start 1.4478 1.7018)
			(end 1.4478 -1.7018)
			(stroke
				(width 0.1524)
				(type default)
			)
			(layer "F.SilkS")
		)
		(fp_line
			(start 1.4478 -1.7018)
			(end -1.4478 -1.7018)
			(stroke
				(width 0.1524)
				(type default)
			)
			(layer "F.SilkS")
		)
		(fp_line
			(start -1.27 1.524)
			(end -1.27 0.6604)
			(stroke
				(width 0.4826)
				(type default)
			)
			(layer "F.SilkS")
		)
		(fp_line
			(start -1.4478 1.7018)
			(end 1.4478 1.7018)
			(stroke
				(width 0.1524)
				(type default)
			)
			(layer "F.SilkS")
		)
		(fp_line
			(start -1.4478 -1.7018)
			(end -1.4478 1.7018)
			(stroke
				(width 0.1524)
				(type default)
			)
			(layer "F.SilkS")
		)
		(fp_poly
			(pts
				(xy -1.524 -1.778) (xy 1.524 -1.778) (xy 1.524 1.778) (xy -1.524 1.778)
			)
			(stroke
				(width 0)
				(type default)
			)
			(fill no)
			(layer "F.CrtYd")
		)
		(fp_poly
			(pts
				(xy -1.524 -1.778) (xy 1.524 -1.778) (xy 1.524 1.778) (xy -1.524 1.778)
			)
			(stroke
				(width 0)
				(type default)
			)
			(fill no)
			(layer "F.Fab")
		)
		(pad "1" smd rect
			(at -0.65024 0.9398 180)
			(size 0.4064 1.016)
			(layers "F.Cu" "F.Mask" "F.Paste")
			(net "GND")
		)
		(pad "2" smd rect
			(at 0 0.9398 180)
			(size 0.4064 1.016)
			(layers "F.Cu" "F.Mask" "F.Paste")
			(net "SW_PWR_R_HDD1")
		)
		(pad "3" smd rect
			(at 0.65024 0.9398 180)
			(size 0.4064 1.016)
			(layers "F.Cu" "F.Mask" "F.Paste")
			(net "SW_HDD_P1")
		)
		(pad "4" smd rect
			(at 0.65024 -0.9398 180)
			(size 0.4064 1.016)
			(layers "F.Cu" "F.Mask" "F.Paste")
			(net "GND")
		)
		(pad "5" smd rect
			(at 0 -0.9398 180)
			(size 0.4064 1.016)
			(layers "F.Cu" "F.Mask" "F.Paste")
			(net "SW_HDD_G1")
		)
		(pad "6" smd rect
			(at -0.65024 -0.9398 180)
			(size 0.4064 1.016)
			(layers "F.Cu" "F.Mask" "F.Paste")
			(net "SW_HDD_R1")
		)
	)
	(footprint ""
		(layer "F.Cu")
		(at 272.542 -337.90509 180)
		(property "Reference" "VIA45"
			(at 0 0 180)
			(layer "F.SilkS")
			(hide yes)
			(effects
				(font
					(size 1.27 1.27)
				)
			)
		)
		(property "Value" "100OHM-8L-1D6MM-L18L16-GP"
			(at -3.7211 -4.5085 180)
			(unlocked yes)
			(layer "F.Fab")
			(hide yes)
			(effects
				(font
					(size 1.016 1.016)
					(thickness 0.1524)
				)
			)
		)
		(property "Device Type" "VIA-PCIE-4P-394076"
			(at -3.7211 -6.0325 180)
			(unlocked yes)
			(layer "F.Fab")
			(hide yes)
			(effects
				(font
					(size 1.016 1.016)
					(thickness 0.1524)
				)
			)
		)
		(duplicate_pad_numbers_are_jumpers no)
		(fp_rect
			(start -1.9685 0.381)
			(end 1.9685 -0.381)
			(stroke
				(width 0)
				(type default)
			)
			(fill no)
			(layer "F.CrtYd")
		)
		(fp_rect
			(start -1.9685 0.381)
			(end 1.9685 -0.381)
			(stroke
				(width 0)
				(type default)
			)
			(fill no)
			(layer "F.Fab")
		)
		(pad "1" thru_hole circle
			(at -1.5875 0 180)
			(size 0.508 0.508)
			(drill 0.254)
			(layers "*.Cu" "*.Mask")
			(remove_unused_layers no)
			(net "GND")
			(clearance 0.127)
			(thermal_gap 0.127)
		)
		(pad "2" thru_hole circle
			(at -0.5715 0 180)
			(size 0.508 0.508)
			(drill 0.254)
			(layers "*.Cu" "*.Mask")
			(remove_unused_layers no)
			(net "PHY_SCC_A_TO_DRV_A_12_DP")
			(clearance 0.127)
			(thermal_gap 0.127)
		)
		(pad "3" thru_hole circle
			(at 0.5715 0 180)
			(size 0.508 0.508)
			(drill 0.254)
			(layers "*.Cu" "*.Mask")
			(remove_unused_layers no)
			(net "PHY_SCC_A_TO_DRV_A_12_DN")
			(clearance 0.127)
			(thermal_gap 0.127)
		)
		(pad "4" thru_hole circle
			(at 1.5875 0 180)
			(size 0.508 0.508)
			(drill 0.254)
			(layers "*.Cu" "*.Mask")
			(remove_unused_layers no)
			(net "GND")
			(clearance 0.127)
			(thermal_gap 0.127)
		)
	)
)
